(kicad_pcb
	(version 20260206)
	(generator "pcbnew")
	(generator_version "10.0")
	(general
		(thickness 1.6)
		(legacy_teardrops no)
	)
	(paper "A4")
	(title_block
		(title "pdpb — Lightning_PDPB_BRD.brd")
		(comment 1 "Lightning (Wiwynn / Facebook NVMe JBOF) / footprints 538-544 of 1140")
	)
	(layers
		(0 "F.Cu" signal "TOP")
		(4 "In1.Cu" signal "L2GND")
		(6 "In2.Cu" signal "L3")
		(8 "In3.Cu" signal "L4VCC")
		(10 "In4.Cu" signal "L5VCC")
		(12 "In5.Cu" signal "L6")
		(14 "In6.Cu" signal "L7GND")
		(2 "B.Cu" signal "BOTTOM")
		(9 "F.Adhes" user "F.Adhesive")
		(11 "B.Adhes" user "B.Adhesive")
		(13 "F.Paste" user "Package Geometry/Pastemask Top")
		(15 "B.Paste" user "Package Geometry/Pastemask Bottom")
		(5 "F.SilkS" user "Ref Des/Silkscreen Top")
		(7 "B.SilkS" user "Ref Des/Silkscreen Bottom")
		(1 "F.Mask" user "Board Geometry/Soldermask Top")
		(3 "B.Mask" user "Board Geometry/Soldermask Bottom")
		(17 "Dwgs.User" user "User.Drawings")
		(19 "Cmts.User" user "User.Comments")
		(21 "Eco1.User" user "User.Eco1")
		(23 "Eco2.User" user "User.Eco2")
		(25 "Edge.Cuts" user "Board Geometry/Outline")
		(27 "Margin" user)
		(31 "F.CrtYd" user "Package Geometry/Place Bound Top")
		(29 "B.CrtYd" user "Package Geometry/Place Bound Bottom")
		(35 "F.Fab" user "Ref Des/Assembly Top")
		(33 "B.Fab" user "Ref Des/Assembly Bottom")
	)
	(footprint ""
		(layer "F.Cu")
		(at 29.7688 -88.9 -90)
		(property "Reference" "U18"
			(at 0 0 270)
			(layer "F.SilkS")
			(hide yes)
			(effects
				(font
					(size 1.27 1.27)
				)
			)
		)
		(property "Value" "P2003EVG-GP"
			(at 0 -11.1252 270)
			(unlocked yes)
			(layer "F.Fab")
			(hide yes)
			(effects
				(font
					(size 1.016 1.016)
					(thickness 0.1524)
				)
			)
		)
		(property "Device Type" "SOIC8H79"
			(at 0 -12.6492 270)
			(unlocked yes)
			(layer "F.Fab")
			(hide yes)
			(effects
				(font
					(size 1.016 1.016)
					(thickness 0.1524)
				)
			)
		)
		(duplicate_pad_numbers_are_jumpers no)
		(fp_line
			(start -2.6162 3.429)
			(end -2.6162 1.4732)
			(stroke
				(width 0.4064)
				(type default)
			)
			(layer "F.SilkS")
		)
		(fp_line
			(start -2.7432 1.4224)
			(end 2.1336 1.4224)
			(stroke
				(width 0.1524)
				(type default)
			)
			(layer "F.SilkS")
		)
		(fp_line
			(start 2.1336 1.4224)
			(end 2.1336 -1.4224)
			(stroke
				(width 0.1524)
				(type default)
			)
			(layer "F.SilkS")
		)
		(fp_line
			(start -2.2352 0)
			(end -2.7432 0.508)
			(stroke
				(width 0.1524)
				(type default)
			)
			(layer "F.SilkS")
		)
		(fp_line
			(start -2.7432 -0.508)
			(end -2.2352 0)
			(stroke
				(width 0.1524)
				(type default)
			)
			(layer "F.SilkS")
		)
		(fp_line
			(start -2.7432 -1.4224)
			(end -2.7432 1.4224)
			(stroke
				(width 0.1524)
				(type default)
			)
			(layer "F.SilkS")
		)
		(fp_line
			(start 2.1336 -1.4224)
			(end -2.7432 -1.4224)
			(stroke
				(width 0.1524)
				(type default)
			)
			(layer "F.SilkS")
		)
		(fp_poly
			(pts
				(xy 2.2098 -1.4224) (xy 2.2098 1.4224) (xy -2.2225 1.4224) (xy -2.2225 -1.4224)
			)
			(stroke
				(width 0)
				(type default)
			)
			(fill yes)
			(layer "F.SilkS")
		)
		(fp_rect
			(start -2.4511 2.9972)
			(end 2.4511 -2.9972)
			(stroke
				(width 0)
				(type default)
			)
			(fill no)
			(layer "F.CrtYd")
		)
		(fp_poly
			(pts
				(xy -2.8194 3.6322) (xy -2.8194 -3.6322) (xy 2.8194 -3.6322) (xy 2.8194 -2.2987) (xy 2.4511 -2.2987)
				(xy 2.4511 -2.9972) (xy -2.4511 -2.9972) (xy -2.4511 2.9972) (xy 2.4511 2.9972) (xy 2.4511 -2.286)
				(xy 2.8194 -2.286) (xy 2.8194 3.6322)
			)
			(stroke
				(width 0)
				(type default)
			)
			(fill no)
			(layer "F.CrtYd")
		)
		(fp_rect
			(start -2.8194 3.6322)
			(end 2.8194 -3.6322)
			(stroke
				(width 0)
				(type default)
			)
			(fill no)
			(layer "F.Fab")
		)
		(pad "1" smd rect
			(at -1.905 2.54 270)
			(size 0.635 1.651)
			(layers "F.Cu" "F.Mask" "F.Paste")
			(net "P12V")
		)
		(pad "2" smd rect
			(at -0.635 2.54 270)
			(size 0.635 1.651)
			(layers "F.Cu" "F.Mask" "F.Paste")
			(net "P12V")
		)
		(pad "3" smd rect
			(at 0.635 2.54 270)
			(size 0.635 1.651)
			(layers "F.Cu" "F.Mask" "F.Paste")
			(net "P12V")
		)
		(pad "4" smd rect
			(at 1.905 2.54 270)
			(size 0.635 1.651)
			(layers "F.Cu" "F.Mask" "F.Paste")
			(net "SW_SSD9_N")
		)
		(pad "5" smd rect
			(at 1.905 -2.54 270)
			(size 0.635 1.651)
			(layers "F.Cu" "F.Mask" "F.Paste")
			(net "P12V_SSD9")
		)
		(pad "6" smd rect
			(at 0.635 -2.54 270)
			(size 0.635 1.651)
			(layers "F.Cu" "F.Mask" "F.Paste")
			(net "P12V_SSD9")
		)
		(pad "7" smd rect
			(at -0.635 -2.54 270)
			(size 0.635 1.651)
			(layers "F.Cu" "F.Mask" "F.Paste")
			(net "P12V_SSD9")
		)
		(pad "8" smd rect
			(at -1.905 -2.54 270)
			(size 0.635 1.651)
			(layers "F.Cu" "F.Mask" "F.Paste")
			(net "P12V_SSD9")
		)
	)
	(footprint ""
		(layer "F.Cu")
		(at 210.312 -87.122)
		(property "Reference" "C386"
			(at 0 0 0)
			(layer "F.SilkS")
			(hide yes)
			(effects
				(font
					(size 1.27 1.27)
				)
			)
		)
		(property "Value" "SCD1U25V2KX-2-GP"
			(at 1.1811 -2.7051 0)
			(unlocked yes)
			(layer "F.Fab")
			(hide yes)
			(effects
				(font
					(size 1.016 1.016)
					(thickness 0.1524)
				)
			)
		)
		(property "Device Type" "C402H22"
			(at 1.1811 -4.2291 0)
			(unlocked yes)
			(layer "F.Fab")
			(hide yes)
			(effects
				(font
					(size 1.016 1.016)
					(thickness 0.1524)
				)
			)
		)
		(duplicate_pad_numbers_are_jumpers no)
		(fp_rect
			(start -0.4318 0.9525)
			(end 0.4318 -0.9525)
			(stroke
				(width 0)
				(type default)
			)
			(fill no)
			(layer "F.CrtYd")
		)
		(fp_rect
			(start -0.4318 0.9525)
			(end 0.4318 -0.9525)
			(stroke
				(width 0)
				(type default)
			)
			(fill no)
			(layer "F.Fab")
		)
		(pad "1" smd custom
			(at 0 -0.4445)
			(size 0.1524 0.1524)
			(layers "F.Cu" "F.Mask" "F.Paste")
			(net "P12V")
			(options
				(clearance outline)
				(anchor circle)
			)
			(primitives
				(gr_poly
					(pts
						(arc
							(start 0.3048 -0.2032)
							(mid 0.275042 -0.275042)
							(end 0.2032 -0.3048)
						)
						(arc
							(start -0.2032 -0.3048)
							(mid -0.275042 -0.275042)
							(end -0.3048 -0.2032)
						)
						(arc
							(start -0.3048 0.2032)
							(mid -0.275042 0.275042)
							(end -0.2032 0.3048)
						)
						(arc
							(start 0.2032 0.3048)
							(mid 0.275042 0.275042)
							(end 0.3048 0.2032)
						)
					)
					(width 0)
					(fill yes)
				)
			)
		)
		(pad "2" smd custom
			(at 0 0.4445)
			(size 0.1524 0.1524)
			(layers "F.Cu" "F.Mask" "F.Paste")
			(net "SW_SSD4_N")
			(options
				(clearance outline)
				(anchor circle)
			)
			(primitives
				(gr_poly
					(pts
						(arc
							(start 0.3048 -0.2032)
							(mid 0.275042 -0.275042)
							(end 0.2032 -0.3048)
						)
						(arc
							(start -0.2032 -0.3048)
							(mid -0.275042 -0.275042)
							(end -0.3048 -0.2032)
						)
						(arc
							(start -0.3048 0.2032)
							(mid -0.275042 0.275042)
							(end -0.2032 0.3048)
						)
						(arc
							(start 0.2032 0.3048)
							(mid 0.275042 0.275042)
							(end 0.3048 0.2032)
						)
					)
					(width 0)
					(fill yes)
				)
			)
		)
	)
	(footprint ""
		(layer "F.Cu")
		(at 86.487 -92.964)
		(property "Reference" "R9124"
			(at 0 0 0)
			(layer "F.SilkS")
			(hide yes)
			(effects
				(font
					(size 1.27 1.27)
				)
			)
		)
		(property "Value" "27R2F-GP"
			(at 0.064008 -3.993896 0)
			(unlocked yes)
			(layer "F.Fab")
			(hide yes)
			(effects
				(font
					(size 1.016 1.016)
					(thickness 0.1524)
				)
			)
		)
		(property "Device Type" "R402H16"
			(at 0.064008 -5.517896 0)
			(unlocked yes)
			(layer "F.Fab")
			(hide yes)
			(effects
				(font
					(size 1.016 1.016)
					(thickness 0.1524)
				)
			)
		)
		(duplicate_pad_numbers_are_jumpers no)
		(fp_line
			(start -0.508 -0.9398)
			(end -0.508 0.9398)
			(stroke
				(width 0.1524)
				(type default)
			)
			(layer "F.SilkS")
		)
		(fp_line
			(start 0.508 -0.9398)
			(end -0.508 -0.9398)
			(stroke
				(width 0.1524)
				(type default)
			)
			(layer "F.SilkS")
		)
		(fp_rect
			(start -0.508 0.9398)
			(end 0.508 -0.9398)
			(stroke
				(width 0)
				(type default)
			)
			(fill no)
			(layer "F.CrtYd")
		)
		(fp_rect
			(start -0.508 0.9398)
			(end 0.508 -0.9398)
			(stroke
				(width 0)
				(type default)
			)
			(fill no)
			(layer "F.Fab")
		)
		(pad "1" smd custom
			(at 0 -0.4445)
			(size 0.1397 0.1397)
			(layers "F.Cu" "F.Mask" "F.Paste")
			(net "PE_CLK_100M_DR9_2_R_P")
			(options
				(clearance outline)
				(anchor circle)
			)
			(primitives
				(gr_poly
					(pts
						(arc
							(start -0.1778 -0.2794)
							(mid -0.249642 -0.249642)
							(end -0.2794 -0.1778)
						)
						(arc
							(start -0.2794 0.1778)
							(mid -0.249642 0.249642)
							(end -0.1778 0.2794)
						)
						(arc
							(start 0.1778 0.2794)
							(mid 0.249642 0.249642)
							(end 0.2794 0.1778)
						)
						(arc
							(start 0.2794 -0.1778)
							(mid 0.249642 -0.249642)
							(end 0.1778 -0.2794)
						)
					)
					(width 0)
					(fill yes)
				)
			)
		)
		(pad "2" smd custom
			(at 0 0.4445)
			(size 0.1397 0.1397)
			(layers "F.Cu" "F.Mask" "F.Paste")
			(net "PE_CLK100M_DR9_2_P")
			(options
				(clearance outline)
				(anchor circle)
			)
			(primitives
				(gr_poly
					(pts
						(arc
							(start -0.1778 -0.2794)
							(mid -0.249642 -0.249642)
							(end -0.2794 -0.1778)
						)
						(arc
							(start -0.2794 0.1778)
							(mid -0.249642 0.249642)
							(end -0.1778 0.2794)
						)
						(arc
							(start 0.1778 0.2794)
							(mid 0.249642 0.249642)
							(end 0.2794 0.1778)
						)
						(arc
							(start 0.2794 -0.1778)
							(mid 0.249642 -0.249642)
							(end 0.1778 -0.2794)
						)
					)
					(width 0)
					(fill yes)
				)
			)
		)
	)
	(footprint ""
		(layer "F.Cu")
		(at 97.028 -197.358 180)
		(property "Reference" "R9597"
			(at 0 0 180)
			(layer "F.SilkS")
			(hide yes)
			(effects
				(font
					(size 1.27 1.27)
				)
			)
		)
		(property "Value" "10R2F-L-GP"
			(at 0.064008 -3.993896 180)
			(unlocked yes)
			(layer "F.Fab")
			(hide yes)
			(effects
				(font
					(size 1.016 1.016)
					(thickness 0.1524)
				)
			)
		)
		(property "Device Type" "R402H14"
			(at 0.064008 -5.517896 180)
			(unlocked yes)
			(layer "F.Fab")
			(hide yes)
			(effects
				(font
					(size 1.016 1.016)
					(thickness 0.1524)
				)
			)
		)
		(duplicate_pad_numbers_are_jumpers no)
		(fp_line
			(start 0.508 -0.9398)
			(end -0.508 -0.9398)
			(stroke
				(width 0.1524)
				(type default)
			)
			(layer "F.SilkS")
		)
		(fp_line
			(start -0.508 -0.9398)
			(end -0.508 0.9398)
			(stroke
				(width 0.1524)
				(type default)
			)
			(layer "F.SilkS")
		)
		(fp_rect
			(start -0.508 0.9398)
			(end 0.508 -0.9398)
			(stroke
				(width 0)
				(type default)
			)
			(fill no)
			(layer "F.CrtYd")
		)
		(fp_rect
			(start -0.508 0.9398)
			(end 0.508 -0.9398)
			(stroke
				(width 0)
				(type default)
			)
			(fill no)
			(layer "F.Fab")
		)
		(pad "1" smd custom
			(at 0 -0.4445 180)
			(size 0.1397 0.1397)
			(layers "F.Cu" "F.Mask" "F.Paste")
			(net "SSD4_CLK0_OE_N")
			(options
				(clearance outline)
				(anchor circle)
			)
			(primitives
				(gr_poly
					(pts
						(arc
							(start -0.1778 -0.2794)
							(mid -0.249642 -0.249642)
							(end -0.2794 -0.1778)
						)
						(arc
							(start -0.2794 0.1778)
							(mid -0.249642 0.249642)
							(end -0.1778 0.2794)
						)
						(arc
							(start 0.1778 0.2794)
							(mid 0.249642 0.249642)
							(end 0.2794 0.1778)
						)
						(arc
							(start 0.2794 -0.1778)
							(mid 0.249642 -0.249642)
							(end 0.1778 -0.2794)
						)
					)
					(width 0)
					(fill yes)
				)
			)
		)
		(pad "2" smd custom
			(at 0 0.4445 180)
			(size 0.1397 0.1397)
			(layers "F.Cu" "F.Mask" "F.Paste")
			(net "SSD4_CLK0_OE_R_N")
			(options
				(clearance outline)
				(anchor circle)
			)
			(primitives
				(gr_poly
					(pts
						(arc
							(start -0.1778 -0.2794)
							(mid -0.249642 -0.249642)
							(end -0.2794 -0.1778)
						)
						(arc
							(start -0.2794 0.1778)
							(mid -0.249642 0.249642)
							(end -0.1778 0.2794)
						)
						(arc
							(start 0.1778 0.2794)
							(mid 0.249642 0.249642)
							(end 0.2794 0.1778)
						)
						(arc
							(start 0.2794 -0.1778)
							(mid 0.249642 -0.249642)
							(end 0.1778 -0.2794)
						)
					)
					(width 0)
					(fill yes)
				)
			)
		)
	)
	(footprint ""
		(layer "F.Cu")
		(at 79.1464 -366.522)
		(property "Reference" "SR986"
			(at 0 0 0)
			(layer "F.SilkS")
			(hide yes)
			(effects
				(font
					(size 1.27 1.27)
				)
			)
		)
		(property "Value" "2KR2F-3-GP"
			(at 0.064008 -3.993896 0)
			(unlocked yes)
			(layer "F.Fab")
			(hide yes)
			(effects
				(font
					(size 1.016 1.016)
					(thickness 0.1524)
				)
			)
		)
		(property "Device Type" "R402H16"
			(at 0.064008 -5.517896 0)
			(unlocked yes)
			(layer "F.Fab")
			(hide yes)
			(effects
				(font
					(size 1.016 1.016)
					(thickness 0.1524)
				)
			)
		)
		(duplicate_pad_numbers_are_jumpers no)
		(fp_line
			(start -0.508 -0.9398)
			(end -0.508 0.9398)
			(stroke
				(width 0.1524)
				(type default)
			)
			(layer "F.SilkS")
		)
		(fp_line
			(start 0.508 -0.9398)
			(end -0.508 -0.9398)
			(stroke
				(width 0.1524)
				(type default)
			)
			(layer "F.SilkS")
		)
		(fp_rect
			(start -0.508 0.9398)
			(end 0.508 -0.9398)
			(stroke
				(width 0)
				(type default)
			)
			(fill no)
			(layer "F.CrtYd")
		)
		(fp_rect
			(start -0.508 0.9398)
			(end 0.508 -0.9398)
			(stroke
				(width 0)
				(type default)
			)
			(fill no)
			(layer "F.Fab")
		)
		(pad "1" smd custom
			(at 0 -0.4445)
			(size 0.1397 0.1397)
			(layers "F.Cu" "F.Mask" "F.Paste")
			(net "P3V3")
			(options
				(clearance outline)
				(anchor circle)
			)
			(primitives
				(gr_poly
					(pts
						(arc
							(start -0.1778 -0.2794)
							(mid -0.249642 -0.249642)
							(end -0.2794 -0.1778)
						)
						(arc
							(start -0.2794 0.1778)
							(mid -0.249642 0.249642)
							(end -0.1778 0.2794)
						)
						(arc
							(start 0.1778 0.2794)
							(mid 0.249642 0.249642)
							(end 0.2794 0.1778)
						)
						(arc
							(start 0.2794 -0.1778)
							(mid 0.249642 -0.249642)
							(end 0.1778 -0.2794)
						)
					)
					(width 0)
					(fill yes)
				)
			)
		)
		(pad "2" smd custom
			(at 0 0.4445)
			(size 0.1397 0.1397)
			(layers "F.Cu" "F.Mask" "F.Paste")
			(net "SDA_DR5")
			(options
				(clearance outline)
				(anchor circle)
			)
			(primitives
				(gr_poly
					(pts
						(arc
							(start -0.1778 -0.2794)
							(mid -0.249642 -0.249642)
							(end -0.2794 -0.1778)
						)
						(arc
							(start -0.2794 0.1778)
							(mid -0.249642 0.249642)
							(end -0.1778 0.2794)
						)
						(arc
							(start 0.1778 0.2794)
							(mid 0.249642 0.249642)
							(end 0.2794 0.1778)
						)
						(arc
							(start 0.2794 -0.1778)
							(mid 0.249642 -0.249642)
							(end 0.1778 -0.2794)
						)
					)
					(width 0)
					(fill yes)
				)
			)
		)
	)
	(footprint ""
		(layer "F.Cu")
		(at 93.726 -439.293 180)
		(property "Reference" "C9418"
			(at 0 0 180)
			(layer "F.SilkS")
			(hide yes)
			(effects
				(font
					(size 1.27 1.27)
				)
			)
		)
		(property "Value" "SCD1U16V2KX-3GP"
			(at 1.1811 -2.7051 180)
			(unlocked yes)
			(layer "F.Fab")
			(hide yes)
			(effects
				(font
					(size 1.016 1.016)
					(thickness 0.1524)
				)
			)
		)
		(property "Device Type" "C402H22"
			(at 1.1811 -4.2291 180)
			(unlocked yes)
			(layer "F.Fab")
			(hide yes)
			(effects
				(font
					(size 1.016 1.016)
					(thickness 0.1524)
				)
			)
		)
		(duplicate_pad_numbers_are_jumpers no)
		(fp_rect
			(start -0.4318 0.9525)
			(end 0.4318 -0.9525)
			(stroke
				(width 0)
				(type default)
			)
			(fill no)
			(layer "F.CrtYd")
		)
		(fp_rect
			(start -0.4318 0.9525)
			(end 0.4318 -0.9525)
			(stroke
				(width 0)
				(type default)
			)
			(fill no)
			(layer "F.Fab")
		)
		(pad "1" smd custom
			(at 0 -0.4445 180)
			(size 0.1524 0.1524)
			(layers "F.Cu" "F.Mask" "F.Paste")
			(net "VDD_DIFF_1")
			(options
				(clearance outline)
				(anchor circle)
			)
			(primitives
				(gr_poly
					(pts
						(arc
							(start 0.3048 -0.2032)
							(mid 0.275042 -0.275042)
							(end 0.2032 -0.3048)
						)
						(arc
							(start -0.2032 -0.3048)
							(mid -0.275042 -0.275042)
							(end -0.3048 -0.2032)
						)
						(arc
							(start -0.3048 0.2032)
							(mid -0.275042 0.275042)
							(end -0.2032 0.3048)
						)
						(arc
							(start 0.2032 0.3048)
							(mid 0.275042 0.275042)
							(end 0.3048 0.2032)
						)
					)
					(width 0)
					(fill yes)
				)
			)
		)
		(pad "2" smd custom
			(at 0 0.4445 180)
			(size 0.1524 0.1524)
			(layers "F.Cu" "F.Mask" "F.Paste")
			(net "GND")
			(options
				(clearance outline)
				(anchor circle)
			)
			(primitives
				(gr_poly
					(pts
						(arc
							(start 0.3048 -0.2032)
							(mid 0.275042 -0.275042)
							(end 0.2032 -0.3048)
						)
						(arc
							(start -0.2032 -0.3048)
							(mid -0.275042 -0.275042)
							(end -0.3048 -0.2032)
						)
						(arc
							(start -0.3048 0.2032)
							(mid -0.275042 0.275042)
							(end -0.2032 0.3048)
						)
						(arc
							(start 0.2032 0.3048)
							(mid 0.275042 0.275042)
							(end 0.3048 0.2032)
						)
					)
					(width 0)
					(fill yes)
				)
			)
		)
	)
	(footprint ""
		(layer "F.Cu")
		(at 28.956 -374.65)
		(property "Reference" "R341"
			(at 0 0 0)
			(layer "F.SilkS")
			(hide yes)
			(effects
				(font
					(size 1.27 1.27)
				)
			)
		)
		(property "Value" "4K7R2F-GP"
			(at 0.064008 -3.993896 0)
			(unlocked yes)
			(layer "F.Fab")
			(hide yes)
			(effects
				(font
					(size 1.016 1.016)
					(thickness 0.1524)
				)
			)
		)
		(property "Device Type" "R402H16"
			(at 0.064008 -5.517896 0)
			(unlocked yes)
			(layer "F.Fab")
			(hide yes)
			(effects
				(font
					(size 1.016 1.016)
					(thickness 0.1524)
				)
			)
		)
		(duplicate_pad_numbers_are_jumpers no)
		(fp_line
			(start -0.508 -0.9398)
			(end -0.508 0.9398)
			(stroke
				(width 0.1524)
				(type default)
			)
			(layer "F.SilkS")
		)
		(fp_line
			(start 0.508 -0.9398)
			(end -0.508 -0.9398)
			(stroke
				(width 0.1524)
				(type default)
			)
			(layer "F.SilkS")
		)
		(fp_rect
			(start -0.508 0.9398)
			(end 0.508 -0.9398)
			(stroke
				(width 0)
				(type default)
			)
			(fill no)
			(layer "F.CrtYd")
		)
		(fp_rect
			(start -0.508 0.9398)
			(end 0.508 -0.9398)
			(stroke
				(width 0)
				(type default)
			)
			(fill no)
			(layer "F.Fab")
		)
		(pad "1" smd custom
			(at 0 -0.4445)
			(size 0.1397 0.1397)
			(layers "F.Cu" "F.Mask" "F.Paste")
			(net "I2C_B_TMP4_A0")
			(options
				(clearance outline)
				(anchor circle)
			)
			(primitives
				(gr_poly
					(pts
						(arc
							(start -0.1778 -0.2794)
							(mid -0.249642 -0.249642)
							(end -0.2794 -0.1778)
						)
						(arc
							(start -0.2794 0.1778)
							(mid -0.249642 0.249642)
							(end -0.1778 0.2794)
						)
						(arc
							(start 0.1778 0.2794)
							(mid 0.249642 0.249642)
							(end 0.2794 0.1778)
						)
						(arc
							(start 0.2794 -0.1778)
							(mid 0.249642 -0.249642)
							(end 0.1778 -0.2794)
						)
					)
					(width 0)
					(fill yes)
				)
			)
		)
		(pad "2" smd custom
			(at 0 0.4445)
			(size 0.1397 0.1397)
			(layers "F.Cu" "F.Mask" "F.Paste")
			(net "GND")
			(options
				(clearance outline)
				(anchor circle)
			)
			(primitives
				(gr_poly
					(pts
						(arc
							(start -0.1778 -0.2794)
							(mid -0.249642 -0.249642)
							(end -0.2794 -0.1778)
						)
						(arc
							(start -0.2794 0.1778)
							(mid -0.249642 0.249642)
							(end -0.1778 0.2794)
						)
						(arc
							(start 0.1778 0.2794)
							(mid 0.249642 0.249642)
							(end 0.2794 0.1778)
						)
						(arc
							(start 0.2794 -0.1778)
							(mid 0.249642 -0.249642)
							(end 0.1778 -0.2794)
						)
					)
					(width 0)
					(fill yes)
				)
			)
		)
	)
)
